# S9S_MB_2U (Grand Teton) — schematic netlist excerpt (pin names and nets, part order shuffled) for the footprints in the layout excerpt that follows; sources: Cadence DE-HDL packaged netlist, KiCad conversion of 03242023_DA0F0TMBIJ0_F0T_Motherboard_J_brd_V01_OCP.brd

J76  PICOPROBE_BXA  DELTA-L 4.0 EMPTY  pkg TRIANG_LAUNCH_3PXB  page 308
  \1_p\  = DELTA_L_85_10INCH_BOT_DP
  \2_n\  = DELTA_L_85_10INCH_BOT_DN
  \3_g\  = DELTA_L_GND_1

(kicad_pcb
	(version 20260206)
	(generator "pcbnew")
	(generator_version "10.0")
	(general
		(thickness 1.6)
		(legacy_teardrops no)
	)
	(paper "A4")
	(title_block
		(title "03242023_DA0F0TMBIJ0_F0T_Motherboard_J_brd_V01_OCP.brd")
		(comment 1 "Grand Teton / footprints 4212-4212 of 6105")
	)
	(layers
		(0 "F.Cu" signal "TOP")
		(4 "In1.Cu" signal "GND")
		(6 "In2.Cu" signal "IN1")
		(8 "In3.Cu" signal "GND1")
		(10 "In4.Cu" signal "IN2")
		(12 "In5.Cu" signal "GND2")
		(14 "In6.Cu" signal "IN3")
		(16 "In7.Cu" signal "GND3")
		(18 "In8.Cu" signal "VCC")
		(20 "In9.Cu" signal "VCC1")
		(22 "In10.Cu" signal "GND4")
		(24 "In11.Cu" signal "IN4")
		(26 "In12.Cu" signal "GND5")
		(28 "In13.Cu" signal "IN5")
		(30 "In14.Cu" signal "GND6")
		(32 "In15.Cu" signal "IN6")
		(34 "In16.Cu" signal "GND7")
		(2 "B.Cu" signal "BOTTOM")
		(9 "F.Adhes" user "F.Adhesive")
		(11 "B.Adhes" user "B.Adhesive")
		(13 "F.Paste" user "Package Geometry/Pastemask Top")
		(15 "B.Paste" user "Package Geometry/Pastemask Bottom")
		(5 "F.SilkS" user "Ref Des/Silkscreen Top")
		(7 "B.SilkS" user "Ref Des/Silkscreen Bottom")
		(1 "F.Mask" user "Board Geometry/Soldermask Top")
		(3 "B.Mask" user "Board Geometry/Soldermask Bottom")
		(17 "Dwgs.User" user "User.Drawings")
		(19 "Cmts.User" user "User.Comments")
		(21 "Eco1.User" user "User.Eco1")
		(23 "Eco2.User" user "User.Eco2")
		(25 "Edge.Cuts" user "Board Geometry/Outline")
		(27 "Margin" user)
		(31 "F.CrtYd" user "Package Geometry/Place Bound Top")
		(29 "B.CrtYd" user "Package Geometry/Place Bound Bottom")
		(35 "F.Fab" user "Ref Des/Assembly Top")
		(33 "B.Fab" user "Ref Des/Assembly Bottom")
	)
	(footprint ""
		(layer "B.Cu")
		(at 260.731508 -2.156206 180)
		(property "Reference" "J76"
			(at 4.218178 -1.140206 270)
			(unlocked yes)
			(layer "B.SilkS")
			(effects
				(font
					(size 0.7874 0.5842)
					(thickness 0.1524)
				)
				(justify left mirror)
			)
		)
		(property "Value" ""
			(at 0 0 0)
			(layer "B.Fab")
			(effects
				(font
					(size 1.27 1.27)
				)
				(justify mirror)
			)
		)
		(duplicate_pad_numbers_are_jumpers no)
		(fp_line
			(start 1.2192 2.1082)
			(end 1.2192 -2.1082)
			(stroke
				(width 0.1524)
				(type default)
			)
			(layer "B.SilkS")
		)
		(fp_line
			(start 1.2192 -2.1082)
			(end -1.2192 -2.1082)
			(stroke
				(width 0.1524)
				(type default)
			)
			(layer "B.SilkS")
		)
		(fp_line
			(start -1.2192 2.1082)
			(end 1.2192 2.1082)
			(stroke
				(width 0.1524)
				(type default)
			)
			(layer "B.SilkS")
		)
		(fp_line
			(start -1.2192 -2.1082)
			(end -1.2192 2.1082)
			(stroke
				(width 0.1524)
				(type default)
			)
			(layer "B.SilkS")
		)
		(pad "" np_thru_hole circle
			(at -3.4671 -1.27 90)
			(size 1.0414 1.0414)
			(drill 1.0414)
			(layers "*.Cu" "*.Mask")
			(clearance 0.381)
			(thermal_gap 0.381)
		)
		(pad "" np_thru_hole circle
			(at -3.4671 1.27 90)
			(size 1.0414 1.0414)
			(drill 1.0414)
			(layers "*.Cu" "*.Mask")
			(clearance 0.381)
			(thermal_gap 0.381)
		)
		(pad "" np_thru_hole circle
			(at 2.8829 -1.27 90)
			(size 1.0414 1.0414)
			(drill 1.0414)
			(layers "*.Cu" "*.Mask")
			(clearance 0.381)
			(thermal_gap 0.381)
		)
		(pad "" np_thru_hole circle
			(at 2.8829 1.27 90)
			(size 1.0414 1.0414)
			(drill 1.0414)
			(layers "*.Cu" "*.Mask")
			(clearance 0.381)
			(thermal_gap 0.381)
		)
		(pad "1" smd rect
			(at -0.8255 -0.249936 90)
			(size 0.3048 0.508)
			(layers "B.Cu" "B.Mask" "B.Paste")
			(net "DELTA_L_85_10INCH_BOT_DP")
		)
		(pad "2" smd rect
			(at -0.8255 0.249936 90)
			(size 0.3048 0.508)
			(layers "B.Cu" "B.Mask" "B.Paste")
			(net "DELTA_L_85_10INCH_BOT_DN")
		)
		(pad "3" smd circle
			(at 0 0)
			(size 0 0)
			(layers "B.Cu" "B.Mask" "B.Paste")
			(net "DELTA_L_GND_1")
		)
		(zone
			(layers "F.Cu" "B.Cu" "In1.Cu" "In2.Cu" "In3.Cu" "In4.Cu" "In5.Cu" "In6.Cu"
				"In7.Cu" "In8.Cu" "In9.Cu" "In10.Cu" "In11.Cu" "In12.Cu" "In13.Cu" "In14.Cu"
				"In15.Cu" "In16.Cu"
			)
			(hatch none 0.5)
			(connect_pads
				(clearance 0)
			)
			(min_thickness 0.25)
			(keepout
				(tracks not_allowed)
				(vias allowed)
				(pads allowed)
				(copperpour not_allowed)
				(footprints allowed)
			)
			(placement
				(enabled no)
				(sheetname "")
			)
			(fill
				(thermal_gap 0.5)
				(thermal_bridge_width 0.5)
				(island_removal_mode 0)
			)
			(polygon
				(pts
					(arc
						(start 258.775708 -3.426206)
						(mid 256.921508 -3.426206)
						(end 258.775708 -3.426206)
					)
				)
			)
		)
		(zone
			(layers "F.Cu" "B.Cu" "In1.Cu" "In2.Cu" "In3.Cu" "In4.Cu" "In5.Cu" "In6.Cu"
				"In7.Cu" "In8.Cu" "In9.Cu" "In10.Cu" "In11.Cu" "In12.Cu" "In13.Cu" "In14.Cu"
				"In15.Cu" "In16.Cu"
			)
			(hatch none 0.5)
			(connect_pads
				(clearance 0)
			)
			(min_thickness 0.25)
			(keepout
				(tracks not_allowed)
				(vias allowed)
				(pads allowed)
				(copperpour not_allowed)
				(footprints allowed)
			)
			(placement
				(enabled no)
				(sheetname "")
			)
			(fill
				(thermal_gap 0.5)
				(thermal_bridge_width 0.5)
				(island_removal_mode 0)
			)
			(polygon
				(pts
					(arc
						(start 258.775708 -0.886206)
						(mid 256.921508 -0.886206)
						(end 258.775708 -0.886206)
					)
				)
			)
		)
		(zone
			(layers "F.Cu" "B.Cu" "In1.Cu" "In2.Cu" "In3.Cu" "In4.Cu" "In5.Cu" "In6.Cu"
				"In7.Cu" "In8.Cu" "In9.Cu" "In10.Cu" "In11.Cu" "In12.Cu" "In13.Cu" "In14.Cu"
				"In15.Cu" "In16.Cu"
			)
			(hatch none 0.5)
			(connect_pads
				(clearance 0)
			)
			(min_thickness 0.25)
			(keepout
				(tracks not_allowed)
				(vias allowed)
				(pads allowed)
				(copperpour not_allowed)
				(footprints allowed)
			)
			(placement
				(enabled no)
				(sheetname "")
			)
			(fill
				(thermal_gap 0.5)
				(thermal_bridge_width 0.5)
				(island_removal_mode 0)
			)
			(polygon
				(pts
					(arc
						(start 265.125708 -3.426206)
						(mid 263.271508 -3.426206)
						(end 265.125708 -3.426206)
					)
				)
			)
		)
		(zone
			(layers "F.Cu" "B.Cu" "In1.Cu" "In2.Cu" "In3.Cu" "In4.Cu" "In5.Cu" "In6.Cu"
				"In7.Cu" "In8.Cu" "In9.Cu" "In10.Cu" "In11.Cu" "In12.Cu" "In13.Cu" "In14.Cu"
				"In15.Cu" "In16.Cu"
			)
			(hatch none 0.5)
			(connect_pads
				(clearance 0)
			)
			(min_thickness 0.25)
			(keepout
				(tracks not_allowed)
				(vias allowed)
				(pads allowed)
				(copperpour not_allowed)
				(footprints allowed)
			)
			(placement
				(enabled no)
				(sheetname "")
			)
			(fill
				(thermal_gap 0.5)
				(thermal_bridge_width 0.5)
				(island_removal_mode 0)
			)
			(polygon
				(pts
					(arc
						(start 265.125708 -0.886206)
						(mid 263.271508 -0.886206)
						(end 265.125708 -0.886206)
					)
				)
			)
		)
		(zone
			(layer "B.Cu")
			(hatch none 0.5)
			(connect_pads
				(clearance 0)
			)
			(min_thickness 0.25)
			(keepout
				(tracks not_allowed)
				(vias allowed)
				(pads allowed)
				(copperpour not_allowed)
				(footprints allowed)
			)
			(placement
				(enabled no)
				(sheetname "")
			)
			(fill
				(thermal_gap 0.5)
				(thermal_bridge_width 0.5)
				(island_removal_mode 0)
			)
			(polygon
				(pts
					(xy 261.849108 -1.607566) (xy 261.849108 -1.70307) (xy 261.252208 -1.70307) (xy 261.252208 -2.10947)
					(xy 261.849108 -2.10947) (xy 261.849108 -2.202942) (xy 261.252208 -2.202942) (xy 261.252208 -2.609342)
					(xy 261.849108 -2.609342) (xy 261.849108 -2.704846) (xy 261.150608 -2.704846) (xy 261.150608 -1.607566)
				)
			)
		)
	)
)
